(kicad_pcb
	(version 20241229)
	(generator "pcbnew")
	(generator_version "9.0")
	(general
		(thickness 1.6296)
		(legacy_teardrops no)
	)
	(paper "A3")
	(title_block
		(title "Thunderbolt to 10GbE adapter")
		(date "2026-04-21")
		(rev "1.1.0")
		(company "Antmicro Ltd")
		(comment 1 "www.antmicro.com")
		(comment 9 "footprints 574-577 of 703")
	)
	(layers
		(0 "F.Cu" signal)
		(4 "In1.Cu" signal)
		(6 "In2.Cu" signal)
		(8 "In3.Cu" signal)
		(10 "In4.Cu" signal)
		(12 "In5.Cu" signal)
		(14 "In6.Cu" signal)
		(2 "B.Cu" signal)
		(9 "F.Adhes" user "F.Adhesive")
		(11 "B.Adhes" user "B.Adhesive")
		(13 "F.Paste" user)
		(15 "B.Paste" user)
		(5 "F.SilkS" user "F.Silkscreen")
		(7 "B.SilkS" user "B.Silkscreen")
		(1 "F.Mask" user)
		(3 "B.Mask" user)
		(17 "Dwgs.User" user "User.Drawings")
		(19 "Cmts.User" user "User.Comments")
		(21 "Eco1.User" user "User.Eco1")
		(23 "Eco2.User" user "User.Eco2")
		(25 "Edge.Cuts" user)
		(27 "Margin" user)
		(31 "F.CrtYd" user "F.Courtyard")
		(29 "B.CrtYd" user "B.Courtyard")
		(35 "F.Fab" user)
		(33 "B.Fab" user)
	)
	(footprint "antmicro-footprints:C_0402_1005Metric"
		(layer "B.Cu")
		(at 125.074998 125.425001)
		(descr "Capacitor SMD 0402")
		(tags "capacitor SMD 0402")
		(property "Reference" "C68"
			(at 21.900002 -7.700002 180)
			(layer "B.SilkS")
			(effects
				(font
					(size 0.7 0.7)
					(thickness 0.15)
				)
				(justify mirror)
			)
		)
		(property "Value" "C_1u_0402"
			(at -1.022927 -2.155213 180)
			(layer "B.Fab")
			(effects
				(font
					(size 0.7 0.7)
					(thickness 0.15)
				)
				(justify left bottom mirror)
			)
		)
		(property "Datasheet" "https://product.tdk.com/en/search/capacitor/ceramic/mlcc/info?part_no=C1005X6S1A105K050BC"
			(at 0 0 180)
			(layer "B.Fab")
			(hide yes)
			(effects
				(font
					(size 1.27 1.27)
					(thickness 0.15)
				)
				(justify mirror)
			)
		)
		(property "Description" "SMD Multilayer Ceramic Capacitor, 1 µF, 10 V, 0402 [1005 Metric], ± 10%, X6S, C"
			(at 0 0 180)
			(layer "B.Fab")
			(hide yes)
			(effects
				(font
					(size 1.27 1.27)
					(thickness 0.15)
				)
				(justify mirror)
			)
		)
		(property "MPN" "C1005X6S1A105K050BC"
			(at 0 0 0)
			(unlocked yes)
			(layer "B.Fab")
			(hide yes)
			(effects
				(font
					(size 1 1)
					(thickness 0.15)
				)
				(justify mirror)
			)
		)
		(property "Manufacturer" "TDK"
			(at 0 0 0)
			(unlocked yes)
			(layer "B.Fab")
			(hide yes)
			(effects
				(font
					(size 1 1)
					(thickness 0.15)
				)
				(justify mirror)
			)
		)
		(property "License" "Apache-2.0"
			(at 0 0 0)
			(unlocked yes)
			(layer "B.Fab")
			(hide yes)
			(effects
				(font
					(size 1 1)
					(thickness 0.15)
				)
				(justify mirror)
			)
		)
		(property "Val" "1u"
			(at 0 0 0)
			(unlocked yes)
			(layer "B.Fab")
			(hide yes)
			(effects
				(font
					(size 1 1)
					(thickness 0.15)
				)
				(justify mirror)
			)
		)
		(property "Voltage" ""
			(at 0 0 0)
			(unlocked yes)
			(layer "B.Fab")
			(hide yes)
			(effects
				(font
					(size 1 1)
					(thickness 0.15)
				)
				(justify mirror)
			)
		)
		(property "Dielectric" ""
			(at 0 0 0)
			(unlocked yes)
			(layer "B.Fab")
			(hide yes)
			(effects
				(font
					(size 1 1)
					(thickness 0.15)
				)
				(justify mirror)
			)
		)
		(property "Author" "Antmicro"
			(at 0 0 0)
			(unlocked yes)
			(layer "B.Fab")
			(hide yes)
			(effects
				(font
					(size 1 1)
					(thickness 0.15)
				)
				(justify mirror)
			)
		)
		(sheetname "/TB Controller - Power/")
		(sheetfile "tb-power.kicad_sch")
		(attr smd)
		(fp_rect
			(start -0.925 0.47)
			(end 0.925 -0.47)
			(stroke
				(width 0.05)
				(type default)
			)
			(fill no)
			(layer "B.CrtYd")
		)
		(fp_line
			(start -0.494 -0.248)
			(end -0.494 0.25)
			(stroke
				(width 0.15)
				(type solid)
			)
			(layer "B.Fab")
		)
		(fp_line
			(start -0.494 0.25)
			(end 0.504 0.25)
			(stroke
				(width 0.15)
				(type solid)
			)
			(layer "B.Fab")
		)
		(fp_line
			(start 0.504 -0.248)
			(end -0.494 -0.248)
			(stroke
				(width 0.15)
				(type solid)
			)
			(layer "B.Fab")
		)
		(fp_line
			(start 0.504 0.25)
			(end 0.504 -0.248)
			(stroke
				(width 0.15)
				(type solid)
			)
			(layer "B.Fab")
		)
		(fp_text user "${REFERENCE}"
			(at -0.939 -4.599 180)
			(layer "B.Fab")
			(effects
				(font
					(size 0.7 0.7)
					(thickness 0.15)
				)
				(justify left bottom mirror)
			)
		)
		(fp_text user "Author: Antmicro"
			(at -0.939 -3.399 180)
			(layer "B.Fab")
			(effects
				(font
					(size 0.7 0.7)
					(thickness 0.15)
				)
				(justify left bottom mirror)
			)
		)
		(fp_text user "License: Apache-2.0"
			(at -0.939 -5.799 180)
			(layer "B.Fab")
			(effects
				(font
					(size 0.7 0.7)
					(thickness 0.15)
				)
				(justify left bottom mirror)
			)
		)
		(pad "1" smd roundrect
			(at -0.48 0)
			(size 0.59 0.64)
			(layers "B.Cu" "B.Mask" "B.Paste")
			(roundrect_rratio 0.25)
			(net 23 "GND")
			(pintype "passive")
		)
		(pad "2" smd roundrect
			(at 0.48 0)
			(size 0.59 0.64)
			(layers "B.Cu" "B.Mask" "B.Paste")
			(roundrect_rratio 0.25)
			(net 178 "Net-(U4A-VCC3P3_ANA_USB2)")
			(pintype "passive")
		)
	)
	(footprint "antmicro-footprints:C_Pol_EIA-A"
		(layer "B.Cu")
		(at 146.7 102.7)
		(property "Reference" "C329"
			(at 2.2 -0.4 0)
			(layer "B.SilkS")
			(effects
				(font
					(size 0.7 0.7)
					(thickness 0.15)
				)
				(justify right top mirror)
			)
		)
		(property "Value" "C_Pol_100u_6V_KEMET-T490-A"
			(at 0 -2 0)
			(layer "B.Fab")
			(effects
				(font
					(size 0.7 0.7)
					(thickness 0.15)
				)
				(justify right top mirror)
			)
		)
		(property "Datasheet" "https://www.kemet.com/en/us/capacitors/product/T490A107M006ATE800.html"
			(at 0 0 0)
			(layer "B.Fab")
			(hide yes)
			(effects
				(font
					(size 1.27 1.27)
					(thickness 0.15)
				)
				(justify mirror)
			)
		)
		(property "Description" "Surface Mount Tantalum Capacitor,  Solid SMD 6V 100uF 1206 20% ESR=800mOhms"
			(at 0 0 0)
			(layer "B.Fab")
			(hide yes)
			(effects
				(font
					(size 1.27 1.27)
					(thickness 0.15)
				)
				(justify mirror)
			)
		)
		(property "Val" "100u"
			(at 0 0 0)
			(unlocked yes)
			(layer "B.Fab")
			(hide yes)
			(effects
				(font
					(size 1 1)
					(thickness 0.15)
				)
				(justify mirror)
			)
		)
		(property "MPN" "T490A107M006ATE800"
			(at 0 0 0)
			(unlocked yes)
			(layer "B.Fab")
			(hide yes)
			(effects
				(font
					(size 1 1)
					(thickness 0.15)
				)
				(justify mirror)
			)
		)
		(property "Manufacturer" "KEMET"
			(at 0 0 0)
			(unlocked yes)
			(layer "B.Fab")
			(hide yes)
			(effects
				(font
					(size 1 1)
					(thickness 0.15)
				)
				(justify mirror)
			)
		)
		(property "License" "Apache-2.0"
			(at 0 0 0)
			(unlocked yes)
			(layer "B.Fab")
			(hide yes)
			(effects
				(font
					(size 1 1)
					(thickness 0.15)
				)
				(justify mirror)
			)
		)
		(property "Author" "Antmicro"
			(at 0 0 0)
			(unlocked yes)
			(layer "B.Fab")
			(hide yes)
			(effects
				(font
					(size 1 1)
					(thickness 0.15)
				)
				(justify mirror)
			)
		)
		(property "Voltage" "6V"
			(at 0 0 0)
			(unlocked yes)
			(layer "B.Fab")
			(hide yes)
			(effects
				(font
					(size 1 1)
					(thickness 0.15)
				)
				(justify mirror)
			)
		)
		(property "Dielectric" "template_dielectric"
			(at 0 0 0)
			(unlocked yes)
			(layer "B.Fab")
			(hide yes)
			(effects
				(font
					(size 1 1)
					(thickness 0.15)
				)
				(justify mirror)
			)
		)
		(sheetname "/X710-AT2 power/")
		(sheetfile "x710-at2-power.kicad_sch")
		(attr smd)
		(fp_line
			(start -2.1 1.1)
			(end -1.8 1.1)
			(stroke
				(width 0.12)
				(type solid)
			)
			(layer "B.SilkS")
		)
		(fp_line
			(start -1.95 1.25)
			(end -1.95 0.95)
			(stroke
				(width 0.12)
				(type solid)
			)
			(layer "B.SilkS")
		)
		(fp_line
			(start -1.5 -0.75)
			(end -1.5 -0.85)
			(stroke
				(width 0.12)
				(type solid)
			)
			(layer "B.SilkS")
		)
		(fp_line
			(start -1.5 0.75)
			(end -1.5 0.85)
			(stroke
				(width 0.12)
				(type solid)
			)
			(layer "B.SilkS")
		)
		(fp_line
			(start -1.5 0.85)
			(end 1.5 0.85)
			(stroke
				(width 0.12)
				(type solid)
			)
			(layer "B.SilkS")
		)
		(fp_line
			(start 1.5 -0.85)
			(end -1.5 -0.85)
			(stroke
				(width 0.12)
				(type solid)
			)
			(layer "B.SilkS")
		)
		(fp_line
			(start 1.5 -0.75)
			(end 1.5 -0.85)
			(stroke
				(width 0.12)
				(type solid)
			)
			(layer "B.SilkS")
		)
		(fp_line
			(start 1.5 0.75)
			(end 1.5 0.85)
			(stroke
				(width 0.12)
				(type solid)
			)
			(layer "B.SilkS")
		)
		(fp_line
			(start -2.05 0.85)
			(end -2.05 -0.85)
			(stroke
				(width 0.05)
				(type solid)
			)
			(layer "B.CrtYd")
		)
		(fp_line
			(start -1.7 -1.05)
			(end -1.7 -0.85)
			(stroke
				(width 0.05)
				(type solid)
			)
			(layer "B.CrtYd")
		)
		(fp_line
			(start -1.7 -0.85)
			(end -2.05 -0.85)
			(stroke
				(width 0.05)
				(type solid)
			)
			(layer "B.CrtYd")
		)
		(fp_line
			(start -1.7 0.85)
			(end -2.05 0.85)
			(stroke
				(width 0.05)
				(type solid)
			)
			(layer "B.CrtYd")
		)
		(fp_line
			(start -1.7 0.85)
			(end -1.7 1.05)
			(stroke
				(width 0.05)
				(type solid)
			)
			(layer "B.CrtYd")
		)
		(fp_line
			(start 1.7 -1.05)
			(end -1.7 -1.05)
			(stroke
				(width 0.05)
				(type solid)
			)
			(layer "B.CrtYd")
		)
		(fp_line
			(start 1.7 -1.05)
			(end 1.7 -0.85)
			(stroke
				(width 0.05)
				(type solid)
			)
			(layer "B.CrtYd")
		)
		(fp_line
			(start 1.7 0.85)
			(end 1.7 1.05)
			(stroke
				(width 0.05)
				(type solid)
			)
			(layer "B.CrtYd")
		)
		(fp_line
			(start 1.7 1.05)
			(end -1.7 1.05)
			(stroke
				(width 0.05)
				(type solid)
			)
			(layer "B.CrtYd")
		)
		(fp_line
			(start 2.05 -0.85)
			(end 1.7 -0.85)
			(stroke
				(width 0.05)
				(type solid)
			)
			(layer "B.CrtYd")
		)
		(fp_line
			(start 2.05 0.85)
			(end 1.7 0.85)
			(stroke
				(width 0.05)
				(type solid)
			)
			(layer "B.CrtYd")
		)
		(fp_line
			(start 2.05 0.85)
			(end 2.05 -0.85)
			(stroke
				(width 0.05)
				(type solid)
			)
			(layer "B.CrtYd")
		)
		(fp_rect
			(start -1.601 0.802)
			(end 1.6 -0.8)
			(stroke
				(width 0.1)
				(type solid)
			)
			(fill no)
			(layer "B.Fab")
		)
		(fp_text user "Author: Antmicro"
			(at -2.1 -6.198 0)
			(layer "B.Fab")
			(effects
				(font
					(size 0.7 0.7)
					(thickness 0.15)
				)
				(justify right top mirror)
			)
		)
		(fp_text user "${REFERENCE}"
			(at -2.1 -4.198 0)
			(layer "B.Fab")
			(effects
				(font
					(size 0.7 0.7)
					(thickness 0.15)
				)
				(justify right top mirror)
			)
		)
		(fp_text user "License: Apache-2.0"
			(at -2.1 -5.198 0)
			(layer "B.Fab")
			(effects
				(font
					(size 0.7 0.7)
					(thickness 0.15)
				)
				(justify right top mirror)
			)
		)
		(pad "1" smd roundrect
			(at -1.2 0)
			(size 1.2 1.2)
			(layers "B.Cu" "B.Mask" "B.Paste")
			(roundrect_rratio 0.1)
			(net 6 "DVDD")
			(pintype "passive")
		)
		(pad "2" smd roundrect
			(at 1.2 0)
			(size 1.2 1.2)
			(layers "B.Cu" "B.Mask" "B.Paste")
			(roundrect_rratio 0.1)
			(net 23 "GND")
			(pintype "passive")
		)
	)
	(footprint "antmicro-footprints:C_0402_1005Metric"
		(layer "B.Cu")
		(at 158.931867 90.695117)
		(descr "Capacitor SMD 0402")
		(tags "capacitor SMD 0402")
		(property "Reference" "C199"
			(at 20.068133 10.984883 180)
			(layer "B.SilkS")
			(effects
				(font
					(size 0.7 0.7)
					(thickness 0.15)
				)
				(justify mirror)
			)
		)
		(property "Value" "C_1u_25V_0402"
			(at -1.022927 -2.155213 180)
			(layer "B.Fab")
			(effects
				(font
					(size 0.7 0.7)
					(thickness 0.15)
				)
				(justify left bottom mirror)
			)
		)
		(property "Datasheet" "https://www.murata.com/products/productdetail?partno=GRM155R61E105KE11%23"
			(at 0 0 180)
			(layer "B.Fab")
			(hide yes)
			(effects
				(font
					(size 1.27 1.27)
					(thickness 0.15)
				)
				(justify mirror)
			)
		)
		(property "Description" "SMD Multilayer Ceramic Capacitor, 1 µF, 25 V, 0402 [1005 Metric], ± 10%, X5R, GRM Series"
			(at 0 0 180)
			(layer "B.Fab")
			(hide yes)
			(effects
				(font
					(size 1.27 1.27)
					(thickness 0.15)
				)
				(justify mirror)
			)
		)
		(property "MPN" "GRM155R61E105KE11J"
			(at 0 0 0)
			(unlocked yes)
			(layer "B.Fab")
			(hide yes)
			(effects
				(font
					(size 1 1)
					(thickness 0.15)
				)
				(justify mirror)
			)
		)
		(property "Manufacturer" "Murata"
			(at 0 0 0)
			(unlocked yes)
			(layer "B.Fab")
			(hide yes)
			(effects
				(font
					(size 1 1)
					(thickness 0.15)
				)
				(justify mirror)
			)
		)
		(property "License" "Apache-2.0"
			(at 0 0 0)
			(unlocked yes)
			(layer "B.Fab")
			(hide yes)
			(effects
				(font
					(size 1 1)
					(thickness 0.15)
				)
				(justify mirror)
			)
		)
		(property "Author" "Antmicro"
			(at 0 0 0)
			(unlocked yes)
			(layer "B.Fab")
			(hide yes)
			(effects
				(font
					(size 1 1)
					(thickness 0.15)
				)
				(justify mirror)
			)
		)
		(property "Val" "1u"
			(at 0 0 0)
			(unlocked yes)
			(layer "B.Fab")
			(hide yes)
			(effects
				(font
					(size 1 1)
					(thickness 0.15)
				)
				(justify mirror)
			)
		)
		(property "Voltage" "25V"
			(at 0 0 0)
			(unlocked yes)
			(layer "B.Fab")
			(hide yes)
			(effects
				(font
					(size 1 1)
					(thickness 0.15)
				)
				(justify mirror)
			)
		)
		(property "Dielectric" "X5R"
			(at 0 0 0)
			(unlocked yes)
			(layer "B.Fab")
			(hide yes)
			(effects
				(font
					(size 1 1)
					(thickness 0.15)
				)
				(justify mirror)
			)
		)
		(sheetname "/X710-AT2 power/")
		(sheetfile "x710-at2-power.kicad_sch")
		(attr smd)
		(fp_rect
			(start -0.925 0.47)
			(end 0.925 -0.47)
			(stroke
				(width 0.05)
				(type default)
			)
			(fill no)
			(layer "B.CrtYd")
		)
		(fp_line
			(start -0.494 -0.248)
			(end -0.494 0.25)
			(stroke
				(width 0.15)
				(type solid)
			)
			(layer "B.Fab")
		)
		(fp_line
			(start -0.494 0.25)
			(end 0.504 0.25)
			(stroke
				(width 0.15)
				(type solid)
			)
			(layer "B.Fab")
		)
		(fp_line
			(start 0.504 -0.248)
			(end -0.494 -0.248)
			(stroke
				(width 0.15)
				(type solid)
			)
			(layer "B.Fab")
		)
		(fp_line
			(start 0.504 0.25)
			(end 0.504 -0.248)
			(stroke
				(width 0.15)
				(type solid)
			)
			(layer "B.Fab")
		)
		(fp_text user "License: Apache-2.0"
			(at -0.939 -5.799 180)
			(layer "B.Fab")
			(effects
				(font
					(size 0.7 0.7)
					(thickness 0.15)
				)
				(justify left bottom mirror)
			)
		)
		(fp_text user "${REFERENCE}"
			(at -0.939 -4.599 180)
			(layer "B.Fab")
			(effects
				(font
					(size 0.7 0.7)
					(thickness 0.15)
				)
				(justify left bottom mirror)
			)
		)
		(fp_text user "Author: Antmicro"
			(at -0.939 -3.399 180)
			(layer "B.Fab")
			(effects
				(font
					(size 0.7 0.7)
					(thickness 0.15)
				)
				(justify left bottom mirror)
			)
		)
		(pad "1" smd roundrect
			(at -0.48 0)
			(size 0.59 0.64)
			(layers "B.Cu" "B.Mask" "B.Paste")
			(roundrect_rratio 0.25)
			(net 23 "GND")
			(pintype "passive")
		)
		(pad "2" smd roundrect
			(at 0.48 0)
			(size 0.59 0.64)
			(layers "B.Cu" "B.Mask" "B.Paste")
			(roundrect_rratio 0.25)
			(net 5 "P0_AVDDL")
			(pintype "passive")
		)
	)
	(footprint "antmicro-footprints:C_0402_1005Metric"
		(layer "B.Cu")
		(at 153.579998 146.66 -90)
		(descr "Capacitor SMD 0402")
		(tags "capacitor SMD 0402")
		(property "Reference" "C302"
			(at 1.09 -0.42 90)
			(layer "B.SilkS")
			(effects
				(font
					(size 0.7 0.7)
					(thickness 0.15)
				)
				(justify left bottom mirror)
			)
		)
		(property "Value" "C_470p_0402"
			(at -1.022927 -2.155213 90)
			(layer "B.Fab")
			(effects
				(font
					(size 0.7 0.7)
					(thickness 0.15)
				)
				(justify left bottom mirror)
			)
		)
		(property "Datasheet" "https://www.passivecomponent.com/wp-content/uploads/datasheet/WTC_MLCC_General_Purpose.pdf"
			(at 0 0 90)
			(layer "B.Fab")
			(hide yes)
			(effects
				(font
					(size 1.27 1.27)
					(thickness 0.15)
				)
				(justify mirror)
			)
		)
		(property "Description" "SMD Multilayer Ceramic Capacitor, General Purpose, 470 pF, 25 V, 0402 [1005 Metric], ± 10%, X7R"
			(at 0 0 90)
			(layer "B.Fab")
			(hide yes)
			(effects
				(font
					(size 1.27 1.27)
					(thickness 0.15)
				)
				(justify mirror)
			)
		)
		(property "MPN" "0402B471K250CT"
			(at 0 0 270)
			(unlocked yes)
			(layer "B.Fab")
			(hide yes)
			(effects
				(font
					(size 1 1)
					(thickness 0.15)
				)
				(justify mirror)
			)
		)
		(property "Manufacturer" "Walsin"
			(at 0 0 270)
			(unlocked yes)
			(layer "B.Fab")
			(hide yes)
			(effects
				(font
					(size 1 1)
					(thickness 0.15)
				)
				(justify mirror)
			)
		)
		(property "License" "Apache-2.0"
			(at 0 0 270)
			(unlocked yes)
			(layer "B.Fab")
			(hide yes)
			(effects
				(font
					(size 1 1)
					(thickness 0.15)
				)
				(justify mirror)
			)
		)
		(property "Author" "Antmicro"
			(at 0 0 270)
			(unlocked yes)
			(layer "B.Fab")
			(hide yes)
			(effects
				(font
					(size 1 1)
					(thickness 0.15)
				)
				(justify mirror)
			)
		)
		(property "Val" "470p"
			(at 0 0 270)
			(unlocked yes)
			(layer "B.Fab")
			(hide yes)
			(effects
				(font
					(size 1 1)
					(thickness 0.15)
				)
				(justify mirror)
			)
		)
		(property "Voltage" "25V"
			(at 0 0 270)
			(unlocked yes)
			(layer "B.Fab")
			(hide yes)
			(effects
				(font
					(size 1 1)
					(thickness 0.15)
				)
				(justify mirror)
			)
		)
		(property "Dielectric" "X7R"
			(at 0 0 270)
			(unlocked yes)
			(layer "B.Fab")
			(hide yes)
			(effects
				(font
					(size 1 1)
					(thickness 0.15)
				)
				(justify mirror)
			)
		)
		(sheetname "/2xRJ45/")
		(sheetfile "2xrj45.kicad_sch")
		(attr smd)
		(fp_rect
			(start -0.925 0.47)
			(end 0.925 -0.47)
			(stroke
				(width 0.05)
				(type default)
			)
			(fill no)
			(layer "B.CrtYd")
		)
		(fp_line
			(start -0.494 0.25)
			(end 0.504 0.25)
			(stroke
				(width 0.15)
				(type solid)
			)
			(layer "B.Fab")
		)
		(fp_line
			(start 0.504 0.25)
			(end 0.504 -0.248)
			(stroke
				(width 0.15)
				(type solid)
			)
			(layer "B.Fab")
		)
		(fp_line
			(start -0.494 -0.248)
			(end -0.494 0.25)
			(stroke
				(width 0.15)
				(type solid)
			)
			(layer "B.Fab")
		)
		(fp_line
			(start 0.504 -0.248)
			(end -0.494 -0.248)
			(stroke
				(width 0.15)
				(type solid)
			)
			(layer "B.Fab")
		)
		(fp_text user "License: Apache-2.0"
			(at -0.939 -5.799 90)
			(layer "B.Fab")
			(effects
				(font
					(size 0.7 0.7)
					(thickness 0.15)
				)
				(justify left bottom mirror)
			)
		)
		(fp_text user "${REFERENCE}"
			(at -0.939 -4.599 90)
			(layer "B.Fab")
			(effects
				(font
					(size 0.7 0.7)
					(thickness 0.15)
				)
				(justify left bottom mirror)
			)
		)
		(fp_text user "Author: Antmicro"
			(at -0.939 -3.399 90)
			(layer "B.Fab")
			(effects
				(font
					(size 0.7 0.7)
					(thickness 0.15)
				)
				(justify left bottom mirror)
			)
		)
		(pad "1" smd roundrect
			(at -0.48 0 270)
			(size 0.59 0.64)
			(layers "B.Cu" "B.Mask" "B.Paste")
			(roundrect_rratio 0.25)
			(net 23 "GND")
			(pintype "passive")
		)
		(pad "2" smd roundrect
			(at 0.48 0 270)
			(size 0.59 0.64)
			(layers "B.Cu" "B.Mask" "B.Paste")
			(roundrect_rratio 0.25)
			(net 406 "Net-(J3-LED_YG_Y-)")
			(pintype "passive")
		)
	)
)
